(kicad_pcb
	(version 20260206)
	(generator "pcbnew")
	(generator_version "10.0")
	(general
		(thickness 1.6)
		(legacy_teardrops no)
	)
	(paper "A4")
	(title_block
		(title "03242023_DA0F0TMBIJ0_F0T_Motherboard_J_brd_V01_OCP.brd")
		(comment 1 "Grand Teton / footprint 1187 of 6105 (U249), pads 207-314 of 484")
	)
	(layers
		(0 "F.Cu" signal "TOP")
		(4 "In1.Cu" signal "GND")
		(6 "In2.Cu" signal "IN1")
		(8 "In3.Cu" signal "GND1")
		(10 "In4.Cu" signal "IN2")
		(12 "In5.Cu" signal "GND2")
		(14 "In6.Cu" signal "IN3")
		(16 "In7.Cu" signal "GND3")
		(18 "In8.Cu" signal "VCC")
		(20 "In9.Cu" signal "VCC1")
		(22 "In10.Cu" signal "GND4")
		(24 "In11.Cu" signal "IN4")
		(26 "In12.Cu" signal "GND5")
		(28 "In13.Cu" signal "IN5")
		(30 "In14.Cu" signal "GND6")
		(32 "In15.Cu" signal "IN6")
		(34 "In16.Cu" signal "GND7")
		(2 "B.Cu" signal "BOTTOM")
		(9 "F.Adhes" user "F.Adhesive")
		(11 "B.Adhes" user "B.Adhesive")
		(13 "F.Paste" user "Package Geometry/Pastemask Top")
		(15 "B.Paste" user "Package Geometry/Pastemask Bottom")
		(5 "F.SilkS" user "Ref Des/Silkscreen Top")
		(7 "B.SilkS" user "Ref Des/Silkscreen Bottom")
		(1 "F.Mask" user "Board Geometry/Soldermask Top")
		(3 "B.Mask" user "Board Geometry/Soldermask Bottom")
		(17 "Dwgs.User" user "User.Drawings")
		(19 "Cmts.User" user "User.Comments")
		(21 "Eco1.User" user "User.Eco1")
		(23 "Eco2.User" user "User.Eco2")
		(25 "Edge.Cuts" user "Board Geometry/Outline")
		(27 "Margin" user)
		(31 "F.CrtYd" user "Package Geometry/Place Bound Top")
		(29 "B.CrtYd" user "Package Geometry/Place Bound Bottom")
		(35 "F.Fab" user "Ref Des/Assembly Top")
		(33 "B.Fab" user "Ref Des/Assembly Bottom")
	)
	(footprint ""
		(layer "F.Cu")
		(at 178.55565 -113.37544 90)
		(property "Reference" "U249"
			(at -11.966194 -11.833098 0)
			(unlocked yes)
			(layer "F.SilkS")
			(effects
				(font
					(size 0.7874 0.5842)
					(thickness 0.1524)
				)
				(justify left)
			)
		)
		(property "Value" ""
			(at 0 0 90)
			(layer "F.Fab")
			(effects
				(font
					(size 1.27 1.27)
				)
			)
		)
		(duplicate_pad_numbers_are_jumpers no)
		(pad "H9" smd circle
			(at -1.999996 -2.800096 90)
			(size 0.4064 0.4064)
			(layers "F.Cu" "F.Mask" "F.Paste")
			(net "P3V3_AUX_FPGA_VCCIO0")
		)
		(pad "H10" smd circle
			(at -1.199896 -2.800096 90)
			(size 0.4064 0.4064)
			(layers "F.Cu" "F.Mask" "F.Paste")
			(net "GND")
		)
		(pad "H11" smd circle
			(at -0.40005 -2.800096 90)
			(size 0.4064 0.4064)
			(layers "F.Cu" "F.Mask" "F.Paste")
			(net "P3V3_AUX_FPGA_VCCIO0")
		)
		(pad "H12" smd circle
			(at 0.40005 -2.800096 90)
			(size 0.4064 0.4064)
			(layers "F.Cu" "F.Mask" "F.Paste")
			(net "P3V3_AUX_FPGA_VCCIO0")
		)
		(pad "H13" smd circle
			(at 1.199896 -2.800096 90)
			(size 0.4064 0.4064)
			(layers "F.Cu" "F.Mask" "F.Paste")
			(net "GND")
		)
		(pad "H14" smd circle
			(at 1.999996 -2.800096 90)
			(size 0.4064 0.4064)
			(layers "F.Cu" "F.Mask" "F.Paste")
			(net "P3V3_AUX_FPGA_VCCIO0")
		)
		(pad "H15" smd circle
			(at 2.800096 -2.800096 90)
			(size 0.4064 0.4064)
			(layers "F.Cu" "F.Mask" "F.Paste")
			(net "GND")
		)
		(pad "H16" smd circle
			(at 3.599942 -2.800096 90)
			(size 0.4064 0.4064)
			(layers "F.Cu" "F.Mask" "F.Paste")
			(net "PWRGD_PS_PWROK_PLD_ISO_R")
		)
		(pad "H17" smd circle
			(at 4.400042 -2.800096 90)
			(size 0.4064 0.4064)
			(layers "F.Cu" "F.Mask" "F.Paste")
			(net "FM_PFR_DSW_PWROK_N")
		)
		(pad "H18" smd circle
			(at 5.199888 -2.800096 90)
			(size 0.4064 0.4064)
			(layers "F.Cu" "F.Mask" "F.Paste")
			(net "PWRGD_PVCCD_HV_CPU1")
		)
		(pad "H19" smd circle
			(at 5.999988 -2.800096 90)
			(size 0.4064 0.4064)
			(layers "F.Cu" "F.Mask" "F.Paste")
			(net "PWRGD_PVCCFA_EHV_FIVRA_CPU1")
		)
		(pad "H20" smd circle
			(at 6.800088 -2.800096 90)
			(size 0.4064 0.4064)
			(layers "F.Cu" "F.Mask" "F.Paste")
			(net "PWRGD_PVCCINFAON_CPU1")
		)
		(pad "H21" smd circle
			(at 7.599934 -2.800096 90)
			(size 0.4064 0.4064)
			(layers "F.Cu" "F.Mask" "F.Paste")
			(net "PWRGD_PVCCFA_EHV_CPU1")
		)
		(pad "H22" smd circle
			(at 8.400034 -2.800096 90)
			(size 0.4064 0.4064)
			(layers "F.Cu" "F.Mask" "F.Paste")
			(net "PWRGD_PVCCFA_EHV_CPU0")
		)
		(pad "J1" smd circle
			(at -8.400034 -1.999996 90)
			(size 0.4064 0.4064)
			(layers "F.Cu" "F.Mask" "F.Paste")
			(net "FAB_BMC_REV_ID2")
		)
		(pad "J2" smd circle
			(at -7.599934 -1.999996 90)
			(size 0.4064 0.4064)
			(layers "F.Cu" "F.Mask" "F.Paste")
			(net "FM_BOARD_BMC_SKU_ID0")
		)
		(pad "J3" smd circle
			(at -6.800088 -1.999996 90)
			(size 0.4064 0.4064)
			(layers "F.Cu" "F.Mask" "F.Paste")
			(net "FM_BOARD_BMC_SKU_ID1")
		)
		(pad "J4" smd circle
			(at -5.999988 -1.999996 90)
			(size 0.4064 0.4064)
			(layers "F.Cu" "F.Mask" "F.Paste")
			(net "FM_BOARD_BMC_SKU_ID2")
		)
		(pad "J5" smd circle
			(at -5.199888 -1.999996 90)
			(size 0.4064 0.4064)
			(layers "F.Cu" "F.Mask" "F.Paste")
			(net "FM_BOARD_BMC_SKU_ID3")
		)
		(pad "J6" smd circle
			(at -4.400042 -1.999996 90)
			(size 0.4064 0.4064)
			(layers "F.Cu" "F.Mask" "F.Paste")
			(net "PWRGD_DRAMPWRGD_CPU1_GH_R_LVC1")
		)
		(pad "J7" smd circle
			(at -3.599942 -1.999996 90)
			(size 0.4064 0.4064)
			(layers "F.Cu" "F.Mask" "F.Paste")
			(net "PWRGD_DRAMPWRGD_CPU1_EF_R_LVC1")
		)
		(pad "J8" smd circle
			(at -2.800096 -1.999996 90)
			(size 0.4064 0.4064)
			(layers "F.Cu" "F.Mask" "F.Paste")
			(net "P3V3_AUX_FPGA_VCCIO5")
		)
		(pad "J9" smd circle
			(at -1.999996 -1.999996 90)
			(size 0.4064 0.4064)
			(layers "F.Cu" "F.Mask" "F.Paste")
			(net "GND")
		)
		(pad "J10" smd circle
			(at -1.199896 -1.999996 90)
			(size 0.4064 0.4064)
			(layers "F.Cu" "F.Mask" "F.Paste")
			(net "GND")
		)
		(pad "J11" smd circle
			(at -0.40005 -1.999996 90)
			(size 0.4064 0.4064)
			(layers "F.Cu" "F.Mask" "F.Paste")
			(net "GND")
		)
		(pad "J12" smd circle
			(at 0.40005 -1.999996 90)
			(size 0.4064 0.4064)
			(layers "F.Cu" "F.Mask" "F.Paste")
			(net "GND")
		)
		(pad "J13" smd circle
			(at 1.199896 -1.999996 90)
			(size 0.4064 0.4064)
			(layers "F.Cu" "F.Mask" "F.Paste")
			(net "GND")
		)
		(pad "J14" smd circle
			(at 1.999996 -1.999996 90)
			(size 0.4064 0.4064)
			(layers "F.Cu" "F.Mask" "F.Paste")
			(net "GND")
		)
		(pad "J15" smd circle
			(at 2.800096 -1.999996 90)
			(size 0.4064 0.4064)
			(layers "F.Cu" "F.Mask" "F.Paste")
			(net "P3V3_AUX_FPGA_VCCIO1")
		)
		(pad "J16" smd circle
			(at 3.599942 -1.999996 90)
			(size 0.4064 0.4064)
			(layers "F.Cu" "F.Mask" "F.Paste")
			(net "PWRGD_P1V05_PCH_AUX")
		)
		(pad "J17" smd circle
			(at 4.400042 -1.999996 90)
			(size 0.4064 0.4064)
			(layers "F.Cu" "F.Mask" "F.Paste")
			(net "PWRGD_P1V8_PCH_AUX_PLD")
		)
		(pad "J18" smd circle
			(at 5.199888 -1.999996 90)
			(size 0.4064 0.4064)
			(layers "F.Cu" "F.Mask" "F.Paste")
			(net "PWRGD_SYS_PWROK_R")
		)
		(pad "J19" smd circle
			(at 5.999988 -1.999996 90)
			(size 0.4064 0.4064)
			(layers "F.Cu" "F.Mask" "F.Paste")
			(net "PWRGD_PCH_PWROK_R")
		)
		(pad "J20" smd circle
			(at 6.800088 -1.999996 90)
			(size 0.4064 0.4064)
			(layers "F.Cu" "F.Mask" "F.Paste")
			(net "E1S_0_P3V3_ADC_ALERT")
		)
		(pad "J21" smd circle
			(at 7.599934 -1.999996 90)
			(size 0.4064 0.4064)
			(layers "F.Cu" "F.Mask" "F.Paste")
			(net "IRQ_PVCCFA_CPU0_VRHOT_R_N")
		)
		(pad "J22" smd circle
			(at 8.400034 -1.999996 90)
			(size 0.4064 0.4064)
			(layers "F.Cu" "F.Mask" "F.Paste")
			(net "IRQ_PVCCFA_CPU1_VRHOT_R_N")
		)
		(pad "K1" smd circle
			(at -8.400034 -1.199896 90)
			(size 0.4064 0.4064)
			(layers "F.Cu" "F.Mask" "F.Paste")
			(net "HP_E1S_0_P3V3_PWRGD_PLD")
		)
		(pad "K2" smd circle
			(at -7.599934 -1.199896 90)
			(size 0.4064 0.4064)
			(layers "F.Cu" "F.Mask" "F.Paste")
			(net "HP_LVC3_E1S_0_HSC_PWRGD_PLD")
		)
		(pad "K3" smd circle
			(at -6.800088 -1.199896 90)
			(size 0.4064 0.4064)
			(layers "F.Cu" "F.Mask" "F.Paste")
			(net "HP_LVC3_OCP_V3_2_PRSNT2_PLD_N")
		)
		(pad "K4" smd circle
			(at -5.999988 -1.199896 90)
			(size 0.4064 0.4064)
			(layers "F.Cu" "F.Mask" "F.Paste")
			(net "HP_LVC3_OCP_V3_1_PRSNT2_PLD_N")
		)
		(pad "K5" smd circle
			(at -5.199888 -1.199896 90)
			(size 0.4064 0.4064)
			(layers "F.Cu" "F.Mask" "F.Paste")
			(net "HP_LVC3_OCP_V3_2_FUSE_PWRGD")
		)
		(pad "K6" smd circle
			(at -4.400042 -1.199896 90)
			(size 0.4064 0.4064)
			(layers "F.Cu" "F.Mask" "F.Paste")
			(net "FAB_BMC_REV_ID0")
		)
		(pad "K7" smd circle
			(at -3.599942 -1.199896 90)
			(size 0.4064 0.4064)
			(layers "F.Cu" "F.Mask" "F.Paste")
			(net "FAB_BMC_REV_ID1")
		)
		(pad "K8" smd circle
			(at -2.800096 -1.199896 90)
			(size 0.4064 0.4064)
			(layers "F.Cu" "F.Mask" "F.Paste")
			(net "P3V3_AUX_FPGA_VCCIO5")
		)
		(pad "K9" smd circle
			(at -1.999996 -1.199896 90)
			(size 0.4064 0.4064)
			(layers "F.Cu" "F.Mask" "F.Paste")
			(net "GND")
		)
		(pad "K10" smd circle
			(at -1.199896 -1.199896 90)
			(size 0.4064 0.4064)
			(layers "F.Cu" "F.Mask" "F.Paste")
			(net "VCC_PLD_CORE")
		)
		(pad "K11" smd circle
			(at -0.40005 -1.199896 90)
			(size 0.4064 0.4064)
			(layers "F.Cu" "F.Mask" "F.Paste")
			(net "VCC_PLD_CORE")
		)
		(pad "K12" smd circle
			(at 0.40005 -1.199896 90)
			(size 0.4064 0.4064)
			(layers "F.Cu" "F.Mask" "F.Paste")
			(net "VCC_PLD_CORE")
		)
		(pad "K13" smd circle
			(at 1.199896 -1.199896 90)
			(size 0.4064 0.4064)
			(layers "F.Cu" "F.Mask" "F.Paste")
			(net "VCC_PLD_CORE")
		)
		(pad "K14" smd circle
			(at 1.999996 -1.199896 90)
			(size 0.4064 0.4064)
			(layers "F.Cu" "F.Mask" "F.Paste")
			(net "GND")
		)
		(pad "K15" smd circle
			(at 2.800096 -1.199896 90)
			(size 0.4064 0.4064)
			(layers "F.Cu" "F.Mask" "F.Paste")
			(net "P3V3_AUX_FPGA_VCCIO1")
		)
		(pad "K16" smd circle
			(at 3.599942 -1.199896 90)
			(size 0.4064 0.4064)
			(layers "F.Cu" "F.Mask" "F.Paste")
			(net "P12V_SCM_ADC_ALERT")
		)
		(pad "K17" smd circle
			(at 4.400042 -1.199896 90)
			(size 0.4064 0.4064)
			(layers "F.Cu" "F.Mask" "F.Paste")
			(net "M2_0_P3V3_ADC_ALERT")
		)
		(pad "K18" smd circle
			(at 5.199888 -1.199896 90)
			(size 0.4064 0.4064)
			(layers "F.Cu" "F.Mask" "F.Paste")
			(net "OCP_V3_2_P3V3_ADC_ALERT")
		)
		(pad "K19" smd circle
			(at 5.999988 -1.199896 90)
			(size 0.4064 0.4064)
			(layers "F.Cu" "F.Mask" "F.Paste")
			(net "NC_FPGA_PR13A")
		)
		(pad "K20" smd circle
			(at 6.800088 -1.199896 90)
			(size 0.4064 0.4064)
			(layers "F.Cu" "F.Mask" "F.Paste")
			(net "OCP_SFF_P3V3_ADC_ALERT")
		)
		(pad "K21" smd circle
			(at 7.599934 -1.199896 90)
			(size 0.4064 0.4064)
			(layers "F.Cu" "F.Mask" "F.Paste")
			(net "GND")
		)
		(pad "K22" smd circle
			(at 8.400034 -1.199896 90)
			(size 0.4064 0.4064)
			(layers "F.Cu" "F.Mask" "F.Paste")
			(net "FM_SOL_UART_CH_SEL")
		)
		(pad "L1" smd circle
			(at -8.400034 -0.40005 90)
			(size 0.4064 0.4064)
			(layers "F.Cu" "F.Mask" "F.Paste")
			(net "Net_1435")
		)
		(pad "L2" smd circle
			(at -7.599934 -0.40005 90)
			(size 0.4064 0.4064)
			(layers "F.Cu" "F.Mask" "F.Paste")
			(net "GND")
		)
		(pad "L3" smd circle
			(at -6.800088 -0.40005 90)
			(size 0.4064 0.4064)
			(layers "F.Cu" "F.Mask" "F.Paste")
			(net "Net_1437")
		)
		(pad "L4" smd circle
			(at -5.999988 -0.40005 90)
			(size 0.4064 0.4064)
			(layers "F.Cu" "F.Mask" "F.Paste")
			(net "Net_1438")
		)
		(pad "L5" smd circle
			(at -5.199888 -0.40005 90)
			(size 0.4064 0.4064)
			(layers "F.Cu" "F.Mask" "F.Paste")
			(net "HP_LVC3_SCM_HSC_PWRGD_PLD")
		)
		(pad "L6" smd circle
			(at -4.400042 -0.40005 90)
			(size 0.4064 0.4064)
			(layers "F.Cu" "F.Mask" "F.Paste")
			(net "E1S_0_CLK_OE_N")
		)
		(pad "L7" smd circle
			(at -3.599942 -0.40005 90)
			(size 0.4064 0.4064)
			(layers "F.Cu" "F.Mask" "F.Paste")
			(net "HP_LVC3_OCP_V3_1_FUSE_PWRGD")
		)
		(pad "L8" smd circle
			(at -2.800096 -0.40005 90)
			(size 0.4064 0.4064)
			(layers "F.Cu" "F.Mask" "F.Paste")
			(net "P3V3_AUX_FPGA_VCCIO4")
		)
		(pad "L9" smd circle
			(at -1.999996 -0.40005 90)
			(size 0.4064 0.4064)
			(layers "F.Cu" "F.Mask" "F.Paste")
			(net "GND")
		)
		(pad "L10" smd circle
			(at -1.199896 -0.40005 90)
			(size 0.4064 0.4064)
			(layers "F.Cu" "F.Mask" "F.Paste")
			(net "GND")
		)
		(pad "L11" smd circle
			(at -0.40005 -0.40005 90)
			(size 0.4064 0.4064)
			(layers "F.Cu" "F.Mask" "F.Paste")
			(net "VCC_PLD_CORE")
		)
		(pad "L12" smd circle
			(at 0.40005 -0.40005 90)
			(size 0.4064 0.4064)
			(layers "F.Cu" "F.Mask" "F.Paste")
			(net "VCC_PLD_CORE")
		)
		(pad "L13" smd circle
			(at 1.199896 -0.40005 90)
			(size 0.4064 0.4064)
			(layers "F.Cu" "F.Mask" "F.Paste")
			(net "GND")
		)
		(pad "L14" smd circle
			(at 1.999996 -0.40005 90)
			(size 0.4064 0.4064)
			(layers "F.Cu" "F.Mask" "F.Paste")
			(net "GND")
		)
		(pad "L15" smd circle
			(at 2.800096 -0.40005 90)
			(size 0.4064 0.4064)
			(layers "F.Cu" "F.Mask" "F.Paste")
			(net "P3V3_AUX_FPGA_VCCIO1")
		)
		(pad "L16" smd circle
			(at 3.599942 -0.40005 90)
			(size 0.4064 0.4064)
			(layers "F.Cu" "F.Mask" "F.Paste")
			(net "NC_FPGA_PR14B")
		)
		(pad "L17" smd circle
			(at 4.400042 -0.40005 90)
			(size 0.4064 0.4064)
			(layers "F.Cu" "F.Mask" "F.Paste")
			(net "NC_FPGA_PR14A")
		)
		(pad "L18" smd circle
			(at 5.199888 -0.40005 90)
			(size 0.4064 0.4064)
			(layers "F.Cu" "F.Mask" "F.Paste")
			(net "GND")
		)
		(pad "L19" smd circle
			(at 5.999988 -0.40005 90)
			(size 0.4064 0.4064)
			(layers "F.Cu" "F.Mask" "F.Paste")
			(net "FM_UARTSW_LSB_N")
		)
		(pad "L20" smd circle
			(at 6.800088 -0.40005 90)
			(size 0.4064 0.4064)
			(layers "F.Cu" "F.Mask" "F.Paste")
			(net "FM_UARTSW_MSB_N")
		)
		(pad "L21" smd circle
			(at 7.599934 -0.40005 90)
			(size 0.4064 0.4064)
			(layers "F.Cu" "F.Mask" "F.Paste")
			(net "FM_THERMAL_ALERT_R_N")
		)
		(pad "L22" smd circle
			(at 8.400034 -0.40005 90)
			(size 0.4064 0.4064)
			(layers "F.Cu" "F.Mask" "F.Paste")
			(net "NC_FPGA_PR16C")
		)
		(pad "M1" smd circle
			(at -8.400034 0.40005 90)
			(size 0.4064 0.4064)
			(layers "F.Cu" "F.Mask" "F.Paste")
			(net "Net_1439")
		)
		(pad "M2" smd circle
			(at -7.599934 0.40005 90)
			(size 0.4064 0.4064)
			(layers "F.Cu" "F.Mask" "F.Paste")
			(net "Net_1436")
		)
		(pad "M3" smd circle
			(at -6.800088 0.40005 90)
			(size 0.4064 0.4064)
			(layers "F.Cu" "F.Mask" "F.Paste")
			(net "P3V3_AUX_FPGA_VCCIO4")
		)
		(pad "M4" smd circle
			(at -5.999988 0.40005 90)
			(size 0.4064 0.4064)
			(layers "F.Cu" "F.Mask" "F.Paste")
			(net "GND")
		)
		(pad "M5" smd circle
			(at -5.199888 0.40005 90)
			(size 0.4064 0.4064)
			(layers "F.Cu" "F.Mask" "F.Paste")
			(net "Net_1442")
		)
		(pad "M6" smd circle
			(at -4.400042 0.40005 90)
			(size 0.4064 0.4064)
			(layers "F.Cu" "F.Mask" "F.Paste")
			(net "Net_1441")
		)
		(pad "M7" smd circle
			(at -3.599942 0.40005 90)
			(size 0.4064 0.4064)
			(layers "F.Cu" "F.Mask" "F.Paste")
			(net "Net_1450")
		)
		(pad "M8" smd circle
			(at -2.800096 0.40005 90)
			(size 0.4064 0.4064)
			(layers "F.Cu" "F.Mask" "F.Paste")
			(net "P3V3_AUX_FPGA_VCCIO4")
		)
		(pad "M9" smd circle
			(at -1.999996 0.40005 90)
			(size 0.4064 0.4064)
			(layers "F.Cu" "F.Mask" "F.Paste")
			(net "GND")
		)
		(pad "M10" smd circle
			(at -1.199896 0.40005 90)
			(size 0.4064 0.4064)
			(layers "F.Cu" "F.Mask" "F.Paste")
			(net "GND")
		)
		(pad "M11" smd circle
			(at -0.40005 0.40005 90)
			(size 0.4064 0.4064)
			(layers "F.Cu" "F.Mask" "F.Paste")
			(net "VCC_PLD_CORE")
		)
		(pad "M12" smd circle
			(at 0.40005 0.40005 90)
			(size 0.4064 0.4064)
			(layers "F.Cu" "F.Mask" "F.Paste")
			(net "VCC_PLD_CORE")
		)
		(pad "M13" smd circle
			(at 1.199896 0.40005 90)
			(size 0.4064 0.4064)
			(layers "F.Cu" "F.Mask" "F.Paste")
			(net "GND")
		)
		(pad "M14" smd circle
			(at 1.999996 0.40005 90)
			(size 0.4064 0.4064)
			(layers "F.Cu" "F.Mask" "F.Paste")
			(net "GND")
		)
		(pad "M15" smd circle
			(at 2.800096 0.40005 90)
			(size 0.4064 0.4064)
			(layers "F.Cu" "F.Mask" "F.Paste")
			(net "P3V3_AUX_FPGA_VCCIO1")
		)
		(pad "M16" smd circle
			(at 3.599942 0.40005 90)
			(size 0.4064 0.4064)
			(layers "F.Cu" "F.Mask" "F.Paste")
			(net "FM_CPU0_SKTOCC_LVT3_PLD_N")
		)
		(pad "M17" smd circle
			(at 4.400042 0.40005 90)
			(size 0.4064 0.4064)
			(layers "F.Cu" "F.Mask" "F.Paste")
			(net "NC_FPGA_PR16D")
		)
		(pad "M18" smd circle
			(at 5.199888 0.40005 90)
			(size 0.4064 0.4064)
			(layers "F.Cu" "F.Mask" "F.Paste")
			(net "P3V3_AUX_FPGA_VCCIO1")
		)
		(pad "M19" smd circle
			(at 5.999988 0.40005 90)
			(size 0.4064 0.4064)
			(layers "F.Cu" "F.Mask" "F.Paste")
			(net "RST_PCIE_CPU1_DEV_PERST_N")
		)
		(pad "M20" smd circle
			(at 6.800088 0.40005 90)
			(size 0.4064 0.4064)
			(layers "F.Cu" "F.Mask" "F.Paste")
			(net "RST_PCIE_CPU0_DEV_PERST_N")
		)
		(pad "M21" smd circle
			(at 7.599934 0.40005 90)
			(size 0.4064 0.4064)
			(layers "F.Cu" "F.Mask" "F.Paste")
			(net "SMB_2_PLD_3V3AUX_SDA_R1")
		)
		(pad "M22" smd circle
			(at 8.400034 0.40005 90)
			(size 0.4064 0.4064)
			(layers "F.Cu" "F.Mask" "F.Paste")
			(net "SMB_2_PLD_3V3AUX_SCL_R1")
		)
		(pad "N1" smd circle
			(at -8.400034 1.199896 90)
			(size 0.4064 0.4064)
			(layers "F.Cu" "F.Mask" "F.Paste")
			(net "Net_1440")
		)
		(pad "N2" smd circle
			(at -7.599934 1.199896 90)
			(size 0.4064 0.4064)
			(layers "F.Cu" "F.Mask" "F.Paste")
			(net "Net_1443")
		)
		(pad "N3" smd circle
			(at -6.800088 1.199896 90)
			(size 0.4064 0.4064)
			(layers "F.Cu" "F.Mask" "F.Paste")
			(net "Net_1445")
		)
		(pad "N4" smd circle
			(at -5.999988 1.199896 90)
			(size 0.4064 0.4064)
			(layers "F.Cu" "F.Mask" "F.Paste")
			(net "Net_1446")
		)
		(pad "N5" smd circle
			(at -5.199888 1.199896 90)
			(size 0.4064 0.4064)
			(layers "F.Cu" "F.Mask" "F.Paste")
			(net "Net_1451")
		)
		(pad "N6" smd circle
			(at -4.400042 1.199896 90)
			(size 0.4064 0.4064)
			(layers "F.Cu" "F.Mask" "F.Paste")
			(net "Net_1452")
		)
	)
)
